(kicad_pcb
	(version 20260206)
	(generator "pcbnew")
	(generator_version "10.0")
	(general
		(thickness 1.6)
		(legacy_teardrops no)
	)
	(paper "A4")
	(title_block
		(title "12092022_DA0F0TMDCD0_F0T_Management_Board_D_brd_V3_OCP.brd")
		(comment 1 "Grand Teton / footprints 237-242 of 1440")
	)
	(layers
		(0 "F.Cu" signal "TOP")
		(4 "In1.Cu" signal "GND")
		(6 "In2.Cu" signal "IN1")
		(8 "In3.Cu" signal "GND1")
		(10 "In4.Cu" signal "IN2")
		(12 "In5.Cu" signal "VCC")
		(14 "In6.Cu" signal "VCC1")
		(16 "In7.Cu" signal "IN3")
		(18 "In8.Cu" signal "GND2")
		(20 "In9.Cu" signal "IN4")
		(22 "In10.Cu" signal "GND3")
		(2 "B.Cu" signal "BOTTOM")
		(9 "F.Adhes" user "F.Adhesive")
		(11 "B.Adhes" user "B.Adhesive")
		(13 "F.Paste" user "Package Geometry/Pastemask Top")
		(15 "B.Paste" user "Package Geometry/Pastemask Bottom")
		(5 "F.SilkS" user "Ref Des/Silkscreen Top")
		(7 "B.SilkS" user "Ref Des/Silkscreen Bottom")
		(1 "F.Mask" user "Board Geometry/Soldermask Top")
		(3 "B.Mask" user "Board Geometry/Soldermask Bottom")
		(17 "Dwgs.User" user "User.Drawings")
		(19 "Cmts.User" user "User.Comments")
		(21 "Eco1.User" user "User.Eco1")
		(23 "Eco2.User" user "User.Eco2")
		(25 "Edge.Cuts" user "Board Geometry/Outline")
		(27 "Margin" user)
		(31 "F.CrtYd" user "Package Geometry/Place Bound Top")
		(29 "B.CrtYd" user "Package Geometry/Place Bound Bottom")
		(35 "F.Fab" user "Ref Des/Assembly Top")
		(33 "B.Fab" user "Ref Des/Assembly Bottom")
	)
	(footprint ""
		(layer "F.Cu")
		(at 33.3248 -66.5226 180)
		(property "Reference" "R758"
			(at 0 0 180)
			(layer "F.SilkS")
			(hide yes)
			(effects
				(font
					(size 1.27 1.27)
				)
			)
		)
		(property "Value" ""
			(at 0 0 180)
			(layer "F.Fab")
			(effects
				(font
					(size 1.27 1.27)
				)
			)
		)
		(duplicate_pad_numbers_are_jumpers no)
		(fp_line
			(start 0.7874 0.4064)
			(end -0.7874 0.4064)
			(stroke
				(width 0.1524)
				(type default)
			)
			(layer "F.SilkS")
		)
		(fp_line
			(start 0.7874 -0.4064)
			(end 0.7874 0.4064)
			(stroke
				(width 0.1524)
				(type default)
			)
			(layer "F.SilkS")
		)
		(fp_line
			(start -0.7874 0.4064)
			(end -0.7874 -0.4064)
			(stroke
				(width 0.1524)
				(type default)
			)
			(layer "F.SilkS")
		)
		(fp_line
			(start -0.7874 -0.4064)
			(end 0.7874 -0.4064)
			(stroke
				(width 0.1524)
				(type default)
			)
			(layer "F.SilkS")
		)
		(fp_line
			(start 0.67945 0.3048)
			(end 0.120396 0.3048)
			(stroke
				(width 0.1)
				(type default)
			)
			(layer "F.Fab")
		)
		(fp_line
			(start 0.67945 -0.3048)
			(end 0.67945 0.3048)
			(stroke
				(width 0.1)
				(type default)
			)
			(layer "F.Fab")
		)
		(fp_line
			(start 0.12065 -0.2794)
			(end 0.12065 -0.3048)
			(stroke
				(width 0.1)
				(type default)
			)
			(layer "F.Fab")
		)
		(fp_line
			(start 0.12065 -0.3048)
			(end 0.67945 -0.3048)
			(stroke
				(width 0.1)
				(type default)
			)
			(layer "F.Fab")
		)
		(fp_line
			(start 0.120396 0.3048)
			(end 0.120396 0.2794)
			(stroke
				(width 0.1)
				(type default)
			)
			(layer "F.Fab")
		)
		(fp_line
			(start 0.120396 0.2794)
			(end -0.12065 0.2794)
			(stroke
				(width 0.1)
				(type default)
			)
			(layer "F.Fab")
		)
		(fp_line
			(start -0.12065 0.3048)
			(end -0.67945 0.3048)
			(stroke
				(width 0.1)
				(type default)
			)
			(layer "F.Fab")
		)
		(fp_line
			(start -0.12065 0.2794)
			(end -0.12065 0.3048)
			(stroke
				(width 0.1)
				(type default)
			)
			(layer "F.Fab")
		)
		(fp_line
			(start -0.12065 -0.2794)
			(end 0.12065 -0.2794)
			(stroke
				(width 0.1)
				(type default)
			)
			(layer "F.Fab")
		)
		(fp_line
			(start -0.12065 -0.305054)
			(end -0.12065 -0.2794)
			(stroke
				(width 0.1)
				(type default)
			)
			(layer "F.Fab")
		)
		(fp_line
			(start -0.67945 0.3048)
			(end -0.67945 -0.305054)
			(stroke
				(width 0.1)
				(type default)
			)
			(layer "F.Fab")
		)
		(fp_line
			(start -0.67945 -0.305054)
			(end -0.12065 -0.305054)
			(stroke
				(width 0.1)
				(type default)
			)
			(layer "F.Fab")
		)
		(pad "1" smd circle
			(at -0.40005 0 180)
			(size 0 0)
			(layers "F.Cu" "F.Mask" "F.Paste")
			(net "P3V3_RGM")
		)
		(pad "2" smd circle
			(at 0.40005 0 180)
			(size 0 0)
			(layers "F.Cu" "F.Mask" "F.Paste")
			(net "UART_BMC_5_RXD_R")
		)
	)
	(footprint ""
		(layer "F.Cu")
		(at 12.319 -98.4758)
		(property "Reference" "R886"
			(at 0 0 0)
			(layer "F.SilkS")
			(hide yes)
			(effects
				(font
					(size 1.27 1.27)
				)
			)
		)
		(property "Value" ""
			(at 0 0 0)
			(layer "F.Fab")
			(effects
				(font
					(size 1.27 1.27)
				)
			)
		)
		(duplicate_pad_numbers_are_jumpers no)
		(fp_line
			(start -0.7874 -0.4064)
			(end 0.7874 -0.4064)
			(stroke
				(width 0.1524)
				(type default)
			)
			(layer "F.SilkS")
		)
		(fp_line
			(start -0.7874 0.4064)
			(end -0.7874 -0.4064)
			(stroke
				(width 0.1524)
				(type default)
			)
			(layer "F.SilkS")
		)
		(fp_line
			(start 0.7874 -0.4064)
			(end 0.7874 0.4064)
			(stroke
				(width 0.1524)
				(type default)
			)
			(layer "F.SilkS")
		)
		(fp_line
			(start 0.7874 0.4064)
			(end -0.7874 0.4064)
			(stroke
				(width 0.1524)
				(type default)
			)
			(layer "F.SilkS")
		)
		(fp_line
			(start -0.67945 -0.305054)
			(end -0.12065 -0.305054)
			(stroke
				(width 0.1)
				(type default)
			)
			(layer "F.Fab")
		)
		(fp_line
			(start -0.67945 0.3048)
			(end -0.67945 -0.305054)
			(stroke
				(width 0.1)
				(type default)
			)
			(layer "F.Fab")
		)
		(fp_line
			(start -0.12065 -0.305054)
			(end -0.12065 -0.2794)
			(stroke
				(width 0.1)
				(type default)
			)
			(layer "F.Fab")
		)
		(fp_line
			(start -0.12065 -0.2794)
			(end 0.12065 -0.2794)
			(stroke
				(width 0.1)
				(type default)
			)
			(layer "F.Fab")
		)
		(fp_line
			(start -0.12065 0.2794)
			(end -0.12065 0.3048)
			(stroke
				(width 0.1)
				(type default)
			)
			(layer "F.Fab")
		)
		(fp_line
			(start -0.12065 0.3048)
			(end -0.67945 0.3048)
			(stroke
				(width 0.1)
				(type default)
			)
			(layer "F.Fab")
		)
		(fp_line
			(start 0.120396 0.2794)
			(end -0.12065 0.2794)
			(stroke
				(width 0.1)
				(type default)
			)
			(layer "F.Fab")
		)
		(fp_line
			(start 0.120396 0.3048)
			(end 0.120396 0.2794)
			(stroke
				(width 0.1)
				(type default)
			)
			(layer "F.Fab")
		)
		(fp_line
			(start 0.12065 -0.3048)
			(end 0.67945 -0.3048)
			(stroke
				(width 0.1)
				(type default)
			)
			(layer "F.Fab")
		)
		(fp_line
			(start 0.12065 -0.2794)
			(end 0.12065 -0.3048)
			(stroke
				(width 0.1)
				(type default)
			)
			(layer "F.Fab")
		)
		(fp_line
			(start 0.67945 -0.3048)
			(end 0.67945 0.3048)
			(stroke
				(width 0.1)
				(type default)
			)
			(layer "F.Fab")
		)
		(fp_line
			(start 0.67945 0.3048)
			(end 0.120396 0.3048)
			(stroke
				(width 0.1)
				(type default)
			)
			(layer "F.Fab")
		)
		(pad "1" smd circle
			(at -0.40005 0)
			(size 0 0)
			(layers "F.Cu" "F.Mask" "F.Paste")
			(net "P3V3_AUX")
		)
		(pad "2" smd circle
			(at 0.40005 0)
			(size 0 0)
			(layers "F.Cu" "F.Mask" "F.Paste")
			(net "PWRGD_P5V_AUX_R1")
		)
	)
	(footprint ""
		(layer "F.Cu")
		(at 41.061894 -22.159976)
		(property "Reference" "L21"
			(at 0 0 0)
			(layer "F.SilkS")
			(hide yes)
			(effects
				(font
					(size 1.27 1.27)
				)
			)
		)
		(property "Value" ""
			(at 0 0 0)
			(layer "F.Fab")
			(effects
				(font
					(size 1.27 1.27)
				)
			)
		)
		(duplicate_pad_numbers_are_jumpers no)
		(fp_line
			(start -0.8636 -1.524)
			(end -0.381508 -1.524)
			(stroke
				(width 0.1524)
				(type default)
			)
			(layer "F.SilkS")
		)
		(fp_line
			(start -0.8636 1.524)
			(end -0.8636 -1.524)
			(stroke
				(width 0.1524)
				(type default)
			)
			(layer "F.SilkS")
		)
		(fp_line
			(start -0.465328 1.524)
			(end -0.8636 1.524)
			(stroke
				(width 0.1524)
				(type default)
			)
			(layer "F.SilkS")
		)
		(fp_line
			(start 0.441452 -1.524)
			(end 0.8636 -1.524)
			(stroke
				(width 0.1524)
				(type default)
			)
			(layer "F.SilkS")
		)
		(fp_line
			(start 0.8636 -1.524)
			(end 0.8636 1.524)
			(stroke
				(width 0.1524)
				(type default)
			)
			(layer "F.SilkS")
		)
		(fp_line
			(start 0.8636 1.524)
			(end 0.492252 1.524)
			(stroke
				(width 0.1524)
				(type default)
			)
			(layer "F.SilkS")
		)
		(fp_poly
			(pts
				(xy -0.875538 -1.918208) (xy -1.414272 -2.09804) (xy -1.055116 -2.457196)
			)
			(stroke
				(width 0)
				(type default)
			)
			(fill yes)
			(layer "F.SilkS")
		)
		(fp_line
			(start -0.700024 -1.100074)
			(end 0.700024 -1.100074)
			(stroke
				(width 0.1)
				(type default)
			)
			(layer "F.Fab")
		)
		(fp_line
			(start -0.700024 1.100074)
			(end -0.700024 -1.100074)
			(stroke
				(width 0.1)
				(type default)
			)
			(layer "F.Fab")
		)
		(fp_line
			(start 0.700024 -1.100074)
			(end 0.700024 1.100074)
			(stroke
				(width 0.1)
				(type default)
			)
			(layer "F.Fab")
		)
		(fp_line
			(start 0.700024 1.100074)
			(end -0.700024 1.100074)
			(stroke
				(width 0.1)
				(type default)
			)
			(layer "F.Fab")
		)
		(fp_poly
			(pts
				(xy -0.4572 -1.6256) (xy -0.7112 -2.1336) (xy -0.2032 -2.1336)
			)
			(stroke
				(width 0)
				(type default)
			)
			(fill yes)
			(layer "F.Fab")
		)
		(pad "1" smd rect
			(at -0.424942 -0.849884)
			(size 0.3556 0.9144)
			(layers "F.Cu" "F.Mask" "F.Paste")
			(net "USB3_01_MUX_FB_TXP")
		)
		(pad "2" smd rect
			(at -0.424942 0.849884)
			(size 0.3556 0.9144)
			(layers "F.Cu" "F.Mask" "F.Paste")
			(net "USB3_01_FB_TXP")
		)
		(pad "3" smd rect
			(at 0.424942 0.849884)
			(size 0.3556 0.9144)
			(layers "F.Cu" "F.Mask" "F.Paste")
			(net "USB3_01_FB_TXN")
		)
		(pad "4" smd rect
			(at 0.424942 -0.849884)
			(size 0.3556 0.9144)
			(layers "F.Cu" "F.Mask" "F.Paste")
			(net "USB3_01_MUX_FB_TXN")
		)
	)
	(footprint ""
		(layer "F.Cu")
		(at 84.201 -94.488)
		(property "Reference" "R97"
			(at 0 0 0)
			(layer "F.SilkS")
			(hide yes)
			(effects
				(font
					(size 1.27 1.27)
				)
			)
		)
		(property "Value" ""
			(at 0 0 0)
			(layer "F.Fab")
			(effects
				(font
					(size 1.27 1.27)
				)
			)
		)
		(duplicate_pad_numbers_are_jumpers no)
		(fp_line
			(start -0.7874 -0.4064)
			(end 0.7874 -0.4064)
			(stroke
				(width 0.1524)
				(type default)
			)
			(layer "F.SilkS")
		)
		(fp_line
			(start -0.7874 0.4064)
			(end -0.7874 -0.4064)
			(stroke
				(width 0.1524)
				(type default)
			)
			(layer "F.SilkS")
		)
		(fp_line
			(start 0.7874 -0.4064)
			(end 0.7874 0.4064)
			(stroke
				(width 0.1524)
				(type default)
			)
			(layer "F.SilkS")
		)
		(fp_line
			(start 0.7874 0.4064)
			(end -0.7874 0.4064)
			(stroke
				(width 0.1524)
				(type default)
			)
			(layer "F.SilkS")
		)
		(fp_line
			(start -0.67945 -0.305054)
			(end -0.12065 -0.305054)
			(stroke
				(width 0.1)
				(type default)
			)
			(layer "F.Fab")
		)
		(fp_line
			(start -0.67945 0.3048)
			(end -0.67945 -0.305054)
			(stroke
				(width 0.1)
				(type default)
			)
			(layer "F.Fab")
		)
		(fp_line
			(start -0.12065 -0.305054)
			(end -0.12065 -0.2794)
			(stroke
				(width 0.1)
				(type default)
			)
			(layer "F.Fab")
		)
		(fp_line
			(start -0.12065 -0.2794)
			(end 0.12065 -0.2794)
			(stroke
				(width 0.1)
				(type default)
			)
			(layer "F.Fab")
		)
		(fp_line
			(start -0.12065 0.2794)
			(end -0.12065 0.3048)
			(stroke
				(width 0.1)
				(type default)
			)
			(layer "F.Fab")
		)
		(fp_line
			(start -0.12065 0.3048)
			(end -0.67945 0.3048)
			(stroke
				(width 0.1)
				(type default)
			)
			(layer "F.Fab")
		)
		(fp_line
			(start 0.120396 0.2794)
			(end -0.12065 0.2794)
			(stroke
				(width 0.1)
				(type default)
			)
			(layer "F.Fab")
		)
		(fp_line
			(start 0.120396 0.3048)
			(end 0.120396 0.2794)
			(stroke
				(width 0.1)
				(type default)
			)
			(layer "F.Fab")
		)
		(fp_line
			(start 0.12065 -0.3048)
			(end 0.67945 -0.3048)
			(stroke
				(width 0.1)
				(type default)
			)
			(layer "F.Fab")
		)
		(fp_line
			(start 0.12065 -0.2794)
			(end 0.12065 -0.3048)
			(stroke
				(width 0.1)
				(type default)
			)
			(layer "F.Fab")
		)
		(fp_line
			(start 0.67945 -0.3048)
			(end 0.67945 0.3048)
			(stroke
				(width 0.1)
				(type default)
			)
			(layer "F.Fab")
		)
		(fp_line
			(start 0.67945 0.3048)
			(end 0.120396 0.3048)
			(stroke
				(width 0.1)
				(type default)
			)
			(layer "F.Fab")
		)
		(pad "1" smd circle
			(at -0.40005 0)
			(size 0 0)
			(layers "F.Cu" "F.Mask" "F.Paste")
			(net "SPI_BMC_TPM_MOSI_R")
		)
		(pad "2" smd circle
			(at 0.40005 0)
			(size 0 0)
			(layers "F.Cu" "F.Mask" "F.Paste")
			(net "SPI_BMC_TPM_MOSI")
		)
	)
	(footprint ""
		(layer "F.Cu")
		(at 10.98296 -78.236318 90)
		(property "Reference" "PC229"
			(at 0 0 90)
			(layer "F.SilkS")
			(hide yes)
			(effects
				(font
					(size 1.27 1.27)
				)
			)
		)
		(property "Value" ""
			(at 0 0 90)
			(layer "F.Fab")
			(effects
				(font
					(size 1.27 1.27)
				)
			)
		)
		(duplicate_pad_numbers_are_jumpers no)
		(fp_line
			(start 1.651 -0.8382)
			(end 1.651 0.8382)
			(stroke
				(width 0.1524)
				(type default)
			)
			(layer "F.SilkS")
		)
		(fp_line
			(start -1.651 -0.8382)
			(end 1.651 -0.8382)
			(stroke
				(width 0.1524)
				(type default)
			)
			(layer "F.SilkS")
		)
		(fp_line
			(start 1.651 0.8382)
			(end -1.651 0.8382)
			(stroke
				(width 0.1524)
				(type default)
			)
			(layer "F.SilkS")
		)
		(fp_line
			(start 0 0.8382)
			(end 0 -0.8382)
			(stroke
				(width 0.1524)
				(type default)
			)
			(layer "F.SilkS")
		)
		(fp_line
			(start -1.651 0.8382)
			(end -1.651 -0.8382)
			(stroke
				(width 0.1524)
				(type default)
			)
			(layer "F.SilkS")
		)
		(fp_line
			(start 1.55956 -0.7366)
			(end 1.524 -0.7366)
			(stroke
				(width 0.1)
				(type default)
			)
			(layer "F.Fab")
		)
		(fp_line
			(start 1.524 -0.7366)
			(end -1.524 -0.7366)
			(stroke
				(width 0.1)
				(type default)
			)
			(layer "F.Fab")
		)
		(fp_line
			(start -1.524 -0.7366)
			(end -1.55956 -0.7366)
			(stroke
				(width 0.1)
				(type default)
			)
			(layer "F.Fab")
		)
		(fp_line
			(start -1.55956 -0.7366)
			(end -1.55956 0.7366)
			(stroke
				(width 0.1)
				(type default)
			)
			(layer "F.Fab")
		)
		(fp_line
			(start 1.55956 0.7366)
			(end 1.55956 -0.7366)
			(stroke
				(width 0.1)
				(type default)
			)
			(layer "F.Fab")
		)
		(fp_line
			(start 1.524 0.7366)
			(end 1.55956 0.7366)
			(stroke
				(width 0.1)
				(type default)
			)
			(layer "F.Fab")
		)
		(fp_line
			(start -1.524 0.7366)
			(end 1.524 0.7366)
			(stroke
				(width 0.1)
				(type default)
			)
			(layer "F.Fab")
		)
		(fp_line
			(start -1.55956 0.7366)
			(end -1.524 0.7366)
			(stroke
				(width 0.1)
				(type default)
			)
			(layer "F.Fab")
		)
		(pad "1" smd rect
			(at -0.94996 0 270)
			(size 1.1176 1.3716)
			(layers "F.Cu" "F.Mask" "F.Paste")
			(net "P3V3_AUX")
		)
		(pad "2" smd rect
			(at 0.94996 0 270)
			(size 1.1176 1.3716)
			(layers "F.Cu" "F.Mask" "F.Paste")
			(net "GND")
		)
	)
	(footprint ""
		(layer "F.Cu")
		(at 13.081 -58.6232 90)
		(property "Reference" "U42"
			(at -2.49047 2.6416 0)
			(unlocked yes)
			(layer "F.SilkS")
			(effects
				(font
					(size 0.7874 0.5842)
					(thickness 0.1524)
				)
			)
		)
		(property "Value" ""
			(at 0 0 90)
			(layer "F.Fab")
			(effects
				(font
					(size 1.27 1.27)
				)
			)
		)
		(duplicate_pad_numbers_are_jumpers no)
		(fp_line
			(start 1.834896 -1.575054)
			(end 1.834896 1.575054)
			(stroke
				(width 0.1524)
				(type default)
			)
			(layer "F.SilkS")
		)
		(fp_line
			(start 0.508 -1.575054)
			(end 1.834896 -1.575054)
			(stroke
				(width 0.1524)
				(type default)
			)
			(layer "F.SilkS")
		)
		(fp_line
			(start -0.508 -1.575054)
			(end 0 -1.016)
			(stroke
				(width 0.1524)
				(type default)
			)
			(layer "F.SilkS")
		)
		(fp_line
			(start -1.834896 -1.575054)
			(end -0.508 -1.575054)
			(stroke
				(width 0.1524)
				(type default)
			)
			(layer "F.SilkS")
		)
		(fp_line
			(start 0 -1.016)
			(end 0.508 -1.575054)
			(stroke
				(width 0.1524)
				(type default)
			)
			(layer "F.SilkS")
		)
		(fp_line
			(start 1.834896 1.575054)
			(end -1.834896 1.575054)
			(stroke
				(width 0.1524)
				(type default)
			)
			(layer "F.SilkS")
		)
		(fp_line
			(start -1.834896 1.575054)
			(end -1.834896 -1.575054)
			(stroke
				(width 0.1524)
				(type default)
			)
			(layer "F.SilkS")
		)
		(fp_poly
			(pts
				(xy -3.003296 -1.45796) (xy -3.003296 -0.44196) (xy -1.987296 -0.94996)
			)
			(stroke
				(width 0)
				(type default)
			)
			(fill yes)
			(layer "F.SilkS")
		)
		(fp_line
			(start 0.824992 -1.575054)
			(end 0.824992 1.575054)
			(stroke
				(width 0.1)
				(type default)
			)
			(layer "F.Fab")
		)
		(fp_line
			(start -0.824992 -1.575054)
			(end 0.824992 -1.575054)
			(stroke
				(width 0.1)
				(type default)
			)
			(layer "F.Fab")
		)
		(fp_line
			(start 0.824992 1.575054)
			(end -0.824992 1.575054)
			(stroke
				(width 0.1)
				(type default)
			)
			(layer "F.Fab")
		)
		(fp_line
			(start -0.824992 1.575054)
			(end -0.824992 -1.575054)
			(stroke
				(width 0.1)
				(type default)
			)
			(layer "F.Fab")
		)
		(fp_poly
			(pts
				(xy -3.003296 -1.45796) (xy -3.003296 -0.44196) (xy -1.987296 -0.94996)
			)
			(stroke
				(width 0)
				(type default)
			)
			(fill yes)
			(layer "F.Fab")
		)
		(pad "1" smd rect
			(at -1.199896 -0.94996)
			(size 0.7112 1.016)
			(layers "F.Cu" "F.Mask" "F.Paste")
			(net "PWRGD_P5V_AUX")
		)
		(pad "2" smd rect
			(at -1.199896 0)
			(size 0.7112 1.016)
			(layers "F.Cu" "F.Mask" "F.Paste")
			(net "PWRGD_P1V8_AUX")
		)
		(pad "3" smd rect
			(at -1.199896 0.94996)
			(size 0.7112 1.016)
			(layers "F.Cu" "F.Mask" "F.Paste")
			(net "GND")
		)
		(pad "4" smd rect
			(at 1.199896 0.94996)
			(size 0.7112 1.016)
			(layers "F.Cu" "F.Mask" "F.Paste")
			(net "EN_P3V3")
		)
		(pad "5" smd rect
			(at 1.199896 -0.94996)
			(size 0.7112 1.016)
			(layers "F.Cu" "F.Mask" "F.Paste")
			(net "P3V3_LDO")
		)
	)
)
